(kicad_pcb
	(version 20260206)
	(generator "pcbnew")
	(generator_version "10.0")
	(general
		(thickness 1.6)
		(legacy_teardrops no)
	)
	(paper "A4")
	(title_block
		(title "Bryce Canyon_F.DPB_16315-1-OCP.brd")
		(comment 1 "Bryce Canyon / footprints 677-680 of 2223")
	)
	(layers
		(0 "F.Cu" signal "TOP")
		(4 "In1.Cu" signal "L2GND")
		(6 "In2.Cu" signal "L3")
		(8 "In3.Cu" signal "L4GND")
		(10 "In4.Cu" signal "L5")
		(12 "In5.Cu" signal "L6VCC")
		(14 "In6.Cu" signal "L7VCC")
		(16 "In7.Cu" signal "L8")
		(18 "In8.Cu" signal "L9GND")
		(20 "In9.Cu" signal "L10")
		(22 "In10.Cu" signal "L11GND")
		(2 "B.Cu" signal "BOTTOM")
		(9 "F.Adhes" user "F.Adhesive")
		(11 "B.Adhes" user "B.Adhesive")
		(13 "F.Paste" user "Package Geometry/Pastemask Top")
		(15 "B.Paste" user "Package Geometry/Pastemask Bottom")
		(5 "F.SilkS" user "Ref Des/Silkscreen Top")
		(7 "B.SilkS" user "Ref Des/Silkscreen Bottom")
		(1 "F.Mask" user "Board Geometry/Soldermask Top")
		(3 "B.Mask" user "Board Geometry/Soldermask Bottom")
		(17 "Dwgs.User" user "User.Drawings")
		(19 "Cmts.User" user "User.Comments")
		(21 "Eco1.User" user "User.Eco1")
		(23 "Eco2.User" user "User.Eco2")
		(25 "Edge.Cuts" user "Board Geometry/Outline")
		(27 "Margin" user)
		(31 "F.CrtYd" user "Package Geometry/Place Bound Top")
		(29 "B.CrtYd" user "Package Geometry/Place Bound Bottom")
		(35 "F.Fab" user "Ref Des/Assembly Top")
		(33 "B.Fab" user "Ref Des/Assembly Bottom")
	)
	(footprint ""
		(layer "F.Cu")
		(at 257.683 -301.244 180)
		(property "Reference" "R5"
			(at 0 0 180)
			(layer "F.SilkS")
			(hide yes)
			(effects
				(font
					(size 1.27 1.27)
				)
			)
		)
		(property "Value" "0R2J-2-GP"
			(at 0.064008 -3.993896 180)
			(unlocked yes)
			(layer "F.Fab")
			(hide yes)
			(effects
				(font
					(size 1.016 1.016)
					(thickness 0.1524)
				)
			)
		)
		(property "Device Type" "R402H16"
			(at 0.064008 -5.517896 180)
			(unlocked yes)
			(layer "F.Fab")
			(hide yes)
			(effects
				(font
					(size 1.016 1.016)
					(thickness 0.1524)
				)
			)
		)
		(duplicate_pad_numbers_are_jumpers no)
		(fp_line
			(start 0.508 -0.9398)
			(end -0.508 -0.9398)
			(stroke
				(width 0.1524)
				(type default)
			)
			(layer "F.SilkS")
		)
		(fp_line
			(start -0.508 -0.9398)
			(end -0.508 0.9398)
			(stroke
				(width 0.1524)
				(type default)
			)
			(layer "F.SilkS")
		)
		(fp_rect
			(start -0.508 0.9398)
			(end 0.508 -0.9398)
			(stroke
				(width 0)
				(type default)
			)
			(fill no)
			(layer "F.CrtYd")
		)
		(fp_rect
			(start -0.508 0.9398)
			(end 0.508 -0.9398)
			(stroke
				(width 0)
				(type default)
			)
			(fill no)
			(layer "F.Fab")
		)
		(pad "1" smd custom
			(at 0 -0.4445 180)
			(size 0.1397 0.1397)
			(layers "F.Cu" "F.Mask" "F.Paste")
			(net "EEPROM_SDA")
			(options
				(clearance outline)
				(anchor circle)
			)
			(primitives
				(gr_poly
					(pts
						(arc
							(start -0.1778 -0.2794)
							(mid -0.249642 -0.249642)
							(end -0.2794 -0.1778)
						)
						(arc
							(start -0.2794 0.1778)
							(mid -0.249642 0.249642)
							(end -0.1778 0.2794)
						)
						(arc
							(start 0.1778 0.2794)
							(mid 0.249642 0.249642)
							(end 0.2794 0.1778)
						)
						(arc
							(start 0.2794 -0.1778)
							(mid 0.249642 -0.249642)
							(end 0.1778 -0.2794)
						)
					)
					(width 0)
					(fill yes)
				)
			)
		)
		(pad "2" smd custom
			(at 0 0.4445 180)
			(size 0.1397 0.1397)
			(layers "F.Cu" "F.Mask" "F.Paste")
			(net "I2C_DPB_A_SDA_BUF")
			(options
				(clearance outline)
				(anchor circle)
			)
			(primitives
				(gr_poly
					(pts
						(arc
							(start -0.1778 -0.2794)
							(mid -0.249642 -0.249642)
							(end -0.2794 -0.1778)
						)
						(arc
							(start -0.2794 0.1778)
							(mid -0.249642 0.249642)
							(end -0.1778 0.2794)
						)
						(arc
							(start 0.1778 0.2794)
							(mid 0.249642 0.249642)
							(end 0.2794 0.1778)
						)
						(arc
							(start 0.2794 -0.1778)
							(mid 0.249642 -0.249642)
							(end 0.1778 -0.2794)
						)
					)
					(width 0)
					(fill yes)
				)
			)
		)
	)
	(footprint ""
		(layer "F.Cu")
		(at 321.634612 -159.219392 -90)
		(property "Reference" "C272"
			(at 0 0 270)
			(layer "F.SilkS")
			(hide yes)
			(effects
				(font
					(size 1.27 1.27)
				)
			)
		)
		(property "Value" "SCD01U16V1KX-GP"
			(at -2.8321 -1.7399 270)
			(unlocked yes)
			(layer "F.Fab")
			(hide yes)
			(effects
				(font
					(size 1.016 1.016)
					(thickness 0.1524)
				)
			)
		)
		(property "Device Type" "C0201H13"
			(at -2.8321 -3.2639 270)
			(unlocked yes)
			(layer "F.Fab")
			(hide yes)
			(effects
				(font
					(size 1.016 1.016)
					(thickness 0.1524)
				)
			)
		)
		(duplicate_pad_numbers_are_jumpers no)
		(fp_rect
			(start -0.2794 0.6477)
			(end 0.2794 -0.6477)
			(stroke
				(width 0)
				(type default)
			)
			(fill no)
			(layer "F.CrtYd")
		)
		(fp_rect
			(start -0.2794 0.6477)
			(end 0.2794 -0.6477)
			(stroke
				(width 0)
				(type default)
			)
			(fill no)
			(layer "F.Fab")
		)
		(pad "1" smd custom
			(at 0 -0.2794 270)
			(size 0.0762 0.0762)
			(layers "F.Cu" "F.Mask" "F.Paste")
			(net "SAS_HDD_RX_N18")
			(options
				(clearance outline)
				(anchor circle)
			)
			(primitives
				(gr_poly
					(pts
						(arc
							(start 0.1524 -0.127)
							(mid 0.137521 -0.162921)
							(end 0.1016 -0.1778)
						)
						(arc
							(start -0.1016 -0.1778)
							(mid -0.137521 -0.162921)
							(end -0.1524 -0.127)
						)
						(arc
							(start -0.1524 0.127)
							(mid -0.137521 0.162921)
							(end -0.1016 0.1778)
						)
						(arc
							(start 0.1016 0.1778)
							(mid 0.137521 0.162921)
							(end 0.1524 0.127)
						)
					)
					(width 0)
					(fill yes)
				)
			)
		)
		(pad "2" smd custom
			(at 0 0.2794 270)
			(size 0.0762 0.0762)
			(layers "F.Cu" "F.Mask" "F.Paste")
			(net "PHY_SCC_A_TO_DRV_A_18_DN")
			(options
				(clearance outline)
				(anchor circle)
			)
			(primitives
				(gr_poly
					(pts
						(arc
							(start 0.1524 -0.127)
							(mid 0.137521 -0.162921)
							(end 0.1016 -0.1778)
						)
						(arc
							(start -0.1016 -0.1778)
							(mid -0.137521 -0.162921)
							(end -0.1524 -0.127)
						)
						(arc
							(start -0.1524 0.127)
							(mid -0.137521 0.162921)
							(end -0.1016 0.1778)
						)
						(arc
							(start 0.1016 0.1778)
							(mid 0.137521 0.162921)
							(end 0.1524 0.127)
						)
					)
					(width 0)
					(fill yes)
				)
			)
		)
	)
	(footprint ""
		(layer "F.Cu")
		(at 469.21293 -130.376168 -90)
		(property "Reference" "R549"
			(at 0 0 270)
			(layer "F.SilkS")
			(hide yes)
			(effects
				(font
					(size 1.27 1.27)
				)
			)
		)
		(property "Value" "4K7R2J-2-GP"
			(at 0.064008 -3.993896 270)
			(unlocked yes)
			(layer "F.Fab")
			(hide yes)
			(effects
				(font
					(size 1.016 1.016)
					(thickness 0.1524)
				)
			)
		)
		(property "Device Type" "R402H16"
			(at 0.064008 -5.517896 270)
			(unlocked yes)
			(layer "F.Fab")
			(hide yes)
			(effects
				(font
					(size 1.016 1.016)
					(thickness 0.1524)
				)
			)
		)
		(duplicate_pad_numbers_are_jumpers no)
		(fp_line
			(start -0.508 -0.9398)
			(end -0.508 0.9398)
			(stroke
				(width 0.1524)
				(type default)
			)
			(layer "F.SilkS")
		)
		(fp_line
			(start 0.508 -0.9398)
			(end -0.508 -0.9398)
			(stroke
				(width 0.1524)
				(type default)
			)
			(layer "F.SilkS")
		)
		(fp_rect
			(start -0.508 0.9398)
			(end 0.508 -0.9398)
			(stroke
				(width 0)
				(type default)
			)
			(fill no)
			(layer "F.CrtYd")
		)
		(fp_rect
			(start -0.508 0.9398)
			(end 0.508 -0.9398)
			(stroke
				(width 0)
				(type default)
			)
			(fill no)
			(layer "F.Fab")
		)
		(pad "1" smd custom
			(at 0 -0.4445 270)
			(size 0.1397 0.1397)
			(layers "F.Cu" "F.Mask" "F.Paste")
			(net "DRIVE_A_23_FLT_LED")
			(options
				(clearance outline)
				(anchor circle)
			)
			(primitives
				(gr_poly
					(pts
						(arc
							(start -0.1778 -0.2794)
							(mid -0.249642 -0.249642)
							(end -0.2794 -0.1778)
						)
						(arc
							(start -0.2794 0.1778)
							(mid -0.249642 0.249642)
							(end -0.1778 0.2794)
						)
						(arc
							(start 0.1778 0.2794)
							(mid 0.249642 0.249642)
							(end 0.2794 0.1778)
						)
						(arc
							(start 0.2794 -0.1778)
							(mid 0.249642 -0.249642)
							(end 0.1778 -0.2794)
						)
					)
					(width 0)
					(fill yes)
				)
			)
		)
		(pad "2" smd custom
			(at 0 0.4445 270)
			(size 0.1397 0.1397)
			(layers "F.Cu" "F.Mask" "F.Paste")
			(net "GND")
			(options
				(clearance outline)
				(anchor circle)
			)
			(primitives
				(gr_poly
					(pts
						(arc
							(start -0.1778 -0.2794)
							(mid -0.249642 -0.249642)
							(end -0.2794 -0.1778)
						)
						(arc
							(start -0.2794 0.1778)
							(mid -0.249642 0.249642)
							(end -0.1778 0.2794)
						)
						(arc
							(start 0.1778 0.2794)
							(mid 0.249642 0.249642)
							(end 0.2794 0.1778)
						)
						(arc
							(start 0.2794 -0.1778)
							(mid 0.249642 -0.249642)
							(end 0.1778 -0.2794)
						)
					)
					(width 0)
					(fill yes)
				)
			)
		)
	)
	(footprint ""
		(layer "F.Cu")
		(at 78.361286 -130.271012 -90)
		(property "Reference" "R510"
			(at 0 0 270)
			(layer "F.SilkS")
			(hide yes)
			(effects
				(font
					(size 1.27 1.27)
				)
			)
		)
		(property "Value" "4K7R2J-2-GP"
			(at 0.064008 -3.993896 270)
			(unlocked yes)
			(layer "F.Fab")
			(hide yes)
			(effects
				(font
					(size 1.016 1.016)
					(thickness 0.1524)
				)
			)
		)
		(property "Device Type" "R402H16"
			(at 0.064008 -5.517896 270)
			(unlocked yes)
			(layer "F.Fab")
			(hide yes)
			(effects
				(font
					(size 1.016 1.016)
					(thickness 0.1524)
				)
			)
		)
		(duplicate_pad_numbers_are_jumpers no)
		(fp_line
			(start -0.508 -0.9398)
			(end -0.508 0.9398)
			(stroke
				(width 0.1524)
				(type default)
			)
			(layer "F.SilkS")
		)
		(fp_line
			(start 0.508 -0.9398)
			(end -0.508 -0.9398)
			(stroke
				(width 0.1524)
				(type default)
			)
			(layer "F.SilkS")
		)
		(fp_rect
			(start -0.508 0.9398)
			(end 0.508 -0.9398)
			(stroke
				(width 0)
				(type default)
			)
			(fill no)
			(layer "F.CrtYd")
		)
		(fp_rect
			(start -0.508 0.9398)
			(end 0.508 -0.9398)
			(stroke
				(width 0)
				(type default)
			)
			(fill no)
			(layer "F.Fab")
		)
		(pad "1" smd custom
			(at 0 -0.4445 270)
			(size 0.1397 0.1397)
			(layers "F.Cu" "F.Mask" "F.Paste")
			(net "DRIVE_A_14_FLT_LED")
			(options
				(clearance outline)
				(anchor circle)
			)
			(primitives
				(gr_poly
					(pts
						(arc
							(start -0.1778 -0.2794)
							(mid -0.249642 -0.249642)
							(end -0.2794 -0.1778)
						)
						(arc
							(start -0.2794 0.1778)
							(mid -0.249642 0.249642)
							(end -0.1778 0.2794)
						)
						(arc
							(start 0.1778 0.2794)
							(mid 0.249642 0.249642)
							(end 0.2794 0.1778)
						)
						(arc
							(start 0.2794 -0.1778)
							(mid 0.249642 -0.249642)
							(end 0.1778 -0.2794)
						)
					)
					(width 0)
					(fill yes)
				)
			)
		)
		(pad "2" smd custom
			(at 0 0.4445 270)
			(size 0.1397 0.1397)
			(layers "F.Cu" "F.Mask" "F.Paste")
			(net "GND")
			(options
				(clearance outline)
				(anchor circle)
			)
			(primitives
				(gr_poly
					(pts
						(arc
							(start -0.1778 -0.2794)
							(mid -0.249642 -0.249642)
							(end -0.2794 -0.1778)
						)
						(arc
							(start -0.2794 0.1778)
							(mid -0.249642 0.249642)
							(end -0.1778 0.2794)
						)
						(arc
							(start 0.1778 0.2794)
							(mid 0.249642 0.249642)
							(end 0.2794 0.1778)
						)
						(arc
							(start 0.2794 -0.1778)
							(mid 0.249642 -0.249642)
							(end 0.1778 -0.2794)
						)
					)
					(width 0)
					(fill yes)
				)
			)
		)
	)
)
